# BASEBOARD_FAB2 (Tioga Pass) — schematic netlist excerpt (pin names and nets, part order shuffled) for the footprints in the layout excerpt that follows; sources: Cadence DE-HDL packaged netlist, KiCad conversion of Wiwynn_Tioga_Pass_MB.brd

R1W23  RES  0.0 5% CHIP  pkg 0402  page 101 : A = SMB_HOST_STBY_LVC3_SDA ; B = SMB_HOST_STBY_LVC3_SDA_R4
R1W7  RES  10.0K 1% CHIP  pkg 0402  page 250 : A = FM_OCP_MEZZC_PRES_LVT3_BMC ; B = P3V3_STBY
RT21  RES  0 5.0% CHIP  pkg 0603  page 224 : A = VR_PVDDQ_GHJ_PH2_BOOT ; B = VR_PVDDQ_GHJ_PH2_BOOT_R

(kicad_pcb
	(version 20260206)
	(generator "pcbnew")
	(generator_version "10.0")
	(general
		(thickness 1.6)
		(legacy_teardrops no)
	)
	(paper "A4")
	(title_block
		(title "Wiwynn_Tioga_Pass_MB.brd")
		(comment 1 "Tioga Pass / footprints 2255-2257 of 4770")
	)
	(layers
		(0 "F.Cu" signal "TOP")
		(4 "In1.Cu" signal "L2GND")
		(6 "In2.Cu" signal "L3")
		(8 "In3.Cu" signal "L4GND")
		(10 "In4.Cu" signal "L5")
		(12 "In5.Cu" signal "L6GND")
		(14 "In6.Cu" signal "L7VCC")
		(16 "In7.Cu" signal "L8VCC")
		(18 "In8.Cu" signal "L9GND")
		(20 "In9.Cu" signal "L10")
		(22 "In10.Cu" signal "L11GND")
		(24 "In11.Cu" signal "L12")
		(26 "In12.Cu" signal "L13GND")
		(2 "B.Cu" signal "BOTTOM")
		(9 "F.Adhes" user "F.Adhesive")
		(11 "B.Adhes" user "B.Adhesive")
		(13 "F.Paste" user "Package Geometry/Pastemask Top")
		(15 "B.Paste" user "Package Geometry/Pastemask Bottom")
		(5 "F.SilkS" user "Ref Des/Silkscreen Top")
		(7 "B.SilkS" user "Ref Des/Silkscreen Bottom")
		(1 "F.Mask" user "Board Geometry/Soldermask Top")
		(3 "B.Mask" user "Board Geometry/Soldermask Bottom")
		(17 "Dwgs.User" user "User.Drawings")
		(19 "Cmts.User" user "User.Comments")
		(21 "Eco1.User" user "User.Eco1")
		(23 "Eco2.User" user "User.Eco2")
		(25 "Edge.Cuts" user "Board Geometry/Outline")
		(27 "Margin" user)
		(31 "F.CrtYd" user "Package Geometry/Place Bound Top")
		(29 "B.CrtYd" user "Package Geometry/Place Bound Bottom")
		(35 "F.Fab" user "Ref Des/Assembly Top")
		(33 "B.Fab" user "Ref Des/Assembly Bottom")
	)
	(footprint ""
		(layer "F.Cu")
		(at -0.2794 -18.2118 90)
		(property "Reference" "RT21"
			(at 1.01473 0.656336 0)
			(unlocked yes)
			(layer "F.SilkS")
			(effects
				(font
					(size 0.4064 0.254)
					(thickness 0.1524)
				)
			)
		)
		(property "Value" ""
			(at 0 0 90)
			(layer "F.Fab")
			(effects
				(font
					(size 1.27 1.27)
				)
			)
		)
		(duplicate_pad_numbers_are_jumpers no)
		(fp_poly
			(pts
				(xy -0.4953 -0.2032) (xy 0.4953 -0.2032) (xy 0.4953 1.6002) (xy -0.4953 1.6002)
			)
			(stroke
				(width 0)
				(type default)
			)
			(fill no)
			(layer "F.CrtYd")
		)
		(fp_line
			(start 0.4953 -0.2032)
			(end 0.4953 1.6002)
			(stroke
				(width 0.1)
				(type default)
			)
			(layer "F.Fab")
		)
		(fp_line
			(start -0.4953 -0.2032)
			(end 0.4953 -0.2032)
			(stroke
				(width 0.1)
				(type default)
			)
			(layer "F.Fab")
		)
		(fp_line
			(start 0.4953 1.6002)
			(end -0.4953 1.6002)
			(stroke
				(width 0.1)
				(type default)
			)
			(layer "F.Fab")
		)
		(fp_line
			(start -0.4953 1.6002)
			(end -0.4953 -0.2032)
			(stroke
				(width 0.1)
				(type default)
			)
			(layer "F.Fab")
		)
		(pad "1" smd rect
			(at 0 0 90)
			(size 0.762 0.889)
			(layers "F.Cu" "F.Mask" "F.Paste")
			(net "VR_PVDDQ_GHJ_PH2_BOOT")
		)
		(pad "2" smd rect
			(at 0 1.397 90)
			(size 0.762 0.889)
			(layers "F.Cu" "F.Mask" "F.Paste")
			(net "VR_PVDDQ_GHJ_PH2_BOOT_R")
		)
		(zone
			(layer "F.Cu")
			(hatch none 0.5)
			(connect_pads
				(clearance 0)
			)
			(min_thickness 0.25)
			(keepout
				(tracks allowed)
				(vias not_allowed)
				(pads allowed)
				(copperpour not_allowed)
				(footprints allowed)
			)
			(placement
				(enabled no)
				(sheetname "")
			)
			(fill
				(thermal_gap 0.5)
				(thermal_bridge_width 0.5)
				(island_removal_mode 0)
			)
			(polygon
				(pts
					(xy 0.6731 -18.5928) (xy 0.1651 -18.5928) (xy 0.1651 -17.8308) (xy 0.6731 -17.8308)
				)
			)
		)
		(zone
			(layer "F.Cu")
			(hatch none 0.5)
			(connect_pads
				(clearance 0)
			)
			(min_thickness 0.25)
			(keepout
				(tracks not_allowed)
				(vias allowed)
				(pads allowed)
				(copperpour not_allowed)
				(footprints allowed)
			)
			(placement
				(enabled no)
				(sheetname "")
			)
			(fill
				(thermal_gap 0.5)
				(thermal_bridge_width 0.5)
				(island_removal_mode 0)
			)
			(polygon
				(pts
					(xy 0.6731 -17.8308) (xy 0.6731 -18.5928) (xy 0.1651 -18.5928) (xy 0.1651 -17.8308)
				)
			)
		)
	)
	(footprint ""
		(layer "F.Cu")
		(at 419.435026 -54.027832 90)
		(property "Reference" "R1W7"
			(at -0.8382 -0.67818 90)
			(unlocked yes)
			(layer "F.SilkS")
			(effects
				(font
					(size 0.4064 0.254)
					(thickness 0.1524)
				)
				(justify left)
			)
		)
		(property "Value" ""
			(at 0 0 90)
			(layer "F.Fab")
			(effects
				(font
					(size 1.27 1.27)
				)
			)
		)
		(duplicate_pad_numbers_are_jumpers no)
		(fp_poly
			(pts
				(xy -0.2794 -0.1016) (xy 0.2794 -0.1016) (xy 0.2794 0.9906) (xy -0.2794 0.9906)
			)
			(stroke
				(width 0)
				(type default)
			)
			(fill no)
			(layer "F.CrtYd")
		)
		(fp_line
			(start 0.2794 -0.1016)
			(end -0.2794 -0.1016)
			(stroke
				(width 0.1)
				(type default)
			)
			(layer "F.Fab")
		)
		(fp_line
			(start -0.2794 -0.1016)
			(end -0.2794 0.9906)
			(stroke
				(width 0.1)
				(type default)
			)
			(layer "F.Fab")
		)
		(fp_line
			(start 0.2794 0.9906)
			(end 0.2794 -0.1016)
			(stroke
				(width 0.1)
				(type default)
			)
			(layer "F.Fab")
		)
		(fp_line
			(start -0.2794 0.9906)
			(end 0.2794 0.9906)
			(stroke
				(width 0.1)
				(type default)
			)
			(layer "F.Fab")
		)
		(pad "1" smd rect
			(at 0 0 90)
			(size 0.508 0.508)
			(layers "F.Cu" "F.Mask" "F.Paste")
			(net "FM_OCP_MEZZC_PRES_LVT3_BMC")
		)
		(pad "2" smd rect
			(at 0 0.889 90)
			(size 0.508 0.508)
			(layers "F.Cu" "F.Mask" "F.Paste")
			(net "P3V3_STBY")
		)
		(zone
			(layer "F.Cu")
			(hatch none 0.5)
			(connect_pads
				(clearance 0)
			)
			(min_thickness 0.25)
			(keepout
				(tracks allowed)
				(vias not_allowed)
				(pads allowed)
				(copperpour not_allowed)
				(footprints allowed)
			)
			(placement
				(enabled no)
				(sheetname "")
			)
			(fill
				(thermal_gap 0.5)
				(thermal_bridge_width 0.5)
				(island_removal_mode 0)
			)
			(polygon
				(pts
					(xy 419.689026 -53.773832) (xy 419.689026 -54.281832) (xy 420.070026 -54.281832) (xy 420.070026 -53.773832)
				)
			)
		)
		(zone
			(layer "F.Cu")
			(hatch none 0.5)
			(connect_pads
				(clearance 0)
			)
			(min_thickness 0.25)
			(keepout
				(tracks not_allowed)
				(vias allowed)
				(pads allowed)
				(copperpour not_allowed)
				(footprints allowed)
			)
			(placement
				(enabled no)
				(sheetname "")
			)
			(fill
				(thermal_gap 0.5)
				(thermal_bridge_width 0.5)
				(island_removal_mode 0)
			)
			(polygon
				(pts
					(xy 420.070026 -53.773832) (xy 420.070026 -54.281832) (xy 419.689026 -54.281832) (xy 419.689026 -53.773832)
				)
			)
		)
	)
	(footprint ""
		(layer "F.Cu")
		(at 472.313 -29.845 90)
		(property "Reference" "R1W23"
			(at -0.8382 -0.67818 90)
			(unlocked yes)
			(layer "F.SilkS")
			(effects
				(font
					(size 0.4064 0.254)
					(thickness 0.1524)
				)
				(justify left)
			)
		)
		(property "Value" ""
			(at 0 0 90)
			(layer "F.Fab")
			(effects
				(font
					(size 1.27 1.27)
				)
			)
		)
		(duplicate_pad_numbers_are_jumpers no)
		(fp_poly
			(pts
				(xy -0.2794 -0.1016) (xy 0.2794 -0.1016) (xy 0.2794 0.9906) (xy -0.2794 0.9906)
			)
			(stroke
				(width 0)
				(type default)
			)
			(fill no)
			(layer "F.CrtYd")
		)
		(fp_line
			(start 0.2794 -0.1016)
			(end -0.2794 -0.1016)
			(stroke
				(width 0.1)
				(type default)
			)
			(layer "F.Fab")
		)
		(fp_line
			(start -0.2794 -0.1016)
			(end -0.2794 0.9906)
			(stroke
				(width 0.1)
				(type default)
			)
			(layer "F.Fab")
		)
		(fp_line
			(start 0.2794 0.9906)
			(end 0.2794 -0.1016)
			(stroke
				(width 0.1)
				(type default)
			)
			(layer "F.Fab")
		)
		(fp_line
			(start -0.2794 0.9906)
			(end 0.2794 0.9906)
			(stroke
				(width 0.1)
				(type default)
			)
			(layer "F.Fab")
		)
		(pad "1" smd rect
			(at 0 0 90)
			(size 0.508 0.508)
			(layers "F.Cu" "F.Mask" "F.Paste")
			(net "SMB_HOST_STBY_LVC3_SDA")
		)
		(pad "2" smd rect
			(at 0 0.889 90)
			(size 0.508 0.508)
			(layers "F.Cu" "F.Mask" "F.Paste")
			(net "SMB_HOST_STBY_LVC3_SDA_R4")
		)
		(zone
			(layer "F.Cu")
			(hatch none 0.5)
			(connect_pads
				(clearance 0)
			)
			(min_thickness 0.25)
			(keepout
				(tracks allowed)
				(vias not_allowed)
				(pads allowed)
				(copperpour not_allowed)
				(footprints allowed)
			)
			(placement
				(enabled no)
				(sheetname "")
			)
			(fill
				(thermal_gap 0.5)
				(thermal_bridge_width 0.5)
				(island_removal_mode 0)
			)
			(polygon
				(pts
					(xy 472.567 -29.591) (xy 472.567 -30.099) (xy 472.948 -30.099) (xy 472.948 -29.591)
				)
			)
		)
		(zone
			(layer "F.Cu")
			(hatch none 0.5)
			(connect_pads
				(clearance 0)
			)
			(min_thickness 0.25)
			(keepout
				(tracks not_allowed)
				(vias allowed)
				(pads allowed)
				(copperpour not_allowed)
				(footprints allowed)
			)
			(placement
				(enabled no)
				(sheetname "")
			)
			(fill
				(thermal_gap 0.5)
				(thermal_bridge_width 0.5)
				(island_removal_mode 0)
			)
			(polygon
				(pts
					(xy 472.948 -29.591) (xy 472.948 -30.099) (xy 472.567 -30.099) (xy 472.567 -29.591)
				)
			)
		)
	)
)
